# TIMECARD (Time Appliance Project (Time Card)) — schematic netlist excerpt (pin names and nets, part order shuffled) for the footprints in the layout excerpt that follows; sources: Cadence DE-HDL packaged netlist, KiCad conversion of R4006-B0001-02_R01.brd

C236  CAPACITOR  0.1UF 25V 10%  pkg SMC_0402R_H022  page 31 : \1\ = XP3R3V_FPGA_SR ; \2\ = SG
R424  RESISTOR  100OHM 1%  pkg SMC_0402R_H016  page 26 : \1\ = FPGA_OUT_SMA4_LED_RED_N ; \2\ = UNNAMED_14_LED4PV14_I268_3

(kicad_pcb
	(version 20260206)
	(generator "pcbnew")
	(generator_version "10.0")
	(general
		(thickness 1.6)
		(legacy_teardrops no)
	)
	(paper "A4")
	(title_block
		(title "timecard-production-celestica-r4006 — R4006-B0001-02_R01.brd")
		(comment 1 "Time Appliance Project (Time Card) / footprints 413-414 of 1113")
	)
	(layers
		(0 "F.Cu" signal "TOP")
		(4 "In1.Cu" signal "L02_GND1")
		(6 "In2.Cu" signal "L03_SIG1")
		(8 "In3.Cu" signal "L04_GND2")
		(10 "In4.Cu" signal "L05_VCC1")
		(12 "In5.Cu" signal "L06_VCC2")
		(14 "In6.Cu" signal "L07_GND3")
		(16 "In7.Cu" signal "L08_SIG2")
		(18 "In8.Cu" signal "L09_GND4")
		(2 "B.Cu" signal "BOTTOM")
		(9 "F.Adhes" user "F.Adhesive")
		(11 "B.Adhes" user "B.Adhesive")
		(13 "F.Paste" user "Package Geometry/Pastemask Top")
		(15 "B.Paste" user "Package Geometry/Pastemask Bottom")
		(5 "F.SilkS" user "Ref Des/Silkscreen Top")
		(7 "B.SilkS" user "Ref Des/Silkscreen Bottom")
		(1 "F.Mask" user "Board Geometry/Soldermask Top")
		(3 "B.Mask" user "Board Geometry/Soldermask Bottom")
		(17 "Dwgs.User" user "User.Drawings")
		(19 "Cmts.User" user "User.Comments")
		(21 "Eco1.User" user "User.Eco1")
		(23 "Eco2.User" user "User.Eco2")
		(25 "Edge.Cuts" user "Board Geometry/Outline")
		(27 "Margin" user)
		(31 "F.CrtYd" user "Package Geometry/Place Bound Top")
		(29 "B.CrtYd" user "Package Geometry/Place Bound Bottom")
		(35 "F.Fab" user "Ref Des/Assembly Top")
		(33 "B.Fab" user "Ref Des/Assembly Bottom")
	)
	(footprint ""
		(layer "F.Cu")
		(at 19.468338 -46.736 180)
		(property "Reference" "R424"
			(at -3.518662 -0.03937 0)
			(unlocked yes)
			(layer "F.SilkS")
			(effects
				(font
					(size 0.7874 0.5842)
					(thickness 0.1524)
				)
			)
		)
		(property "Value" "VAL*"
			(at 0.02032 2.13233 180)
			(unlocked yes)
			(layer "F.Fab")
			(hide yes)
			(effects
				(font
					(size 0.7874 0.5842)
					(thickness 0.1524)
				)
			)
		)
		(property "Device Type" "RESISTOR-G155-11000-01,100OHM,A"
			(at 0.008382 1.210564 180)
			(unlocked yes)
			(layer "F.Fab")
			(hide yes)
			(effects
				(font
					(size 0.7874 0.5842)
					(thickness 0.1524)
				)
			)
		)
		(property "User Part Number" "PARTNUM*"
			(at 0.02032 4.024884 180)
			(unlocked yes)
			(layer "Cmts.User")
			(hide yes)
			(effects
				(font
					(size 0.7874 0.5842)
					(thickness 0.1524)
				)
			)
		)
		(property "Tolerance" "TOL*"
			(at 0.044704 3.05435 180)
			(unlocked yes)
			(layer "Cmts.User")
			(hide yes)
			(effects
				(font
					(size 0.7874 0.5842)
					(thickness 0.1524)
				)
			)
		)
		(duplicate_pad_numbers_are_jumpers no)
		(fp_line
			(start 1.143 0.5588)
			(end 1.143 -0.5588)
			(stroke
				(width 0.1)
				(type default)
			)
			(layer "F.SilkS")
		)
		(fp_line
			(start 1.143 -0.5588)
			(end -1.143 -0.5588)
			(stroke
				(width 0.1)
				(type default)
			)
			(layer "F.SilkS")
		)
		(fp_line
			(start -1.143 0.5588)
			(end 1.143 0.5588)
			(stroke
				(width 0.1)
				(type default)
			)
			(layer "F.SilkS")
		)
		(fp_line
			(start -1.143 -0.5588)
			(end -1.143 0.5588)
			(stroke
				(width 0.1)
				(type default)
			)
			(layer "F.SilkS")
		)
		(fp_poly
			(pts
				(xy -1.143 0.5588) (xy 1.143 0.5588) (xy 1.143 -0.5588) (xy -1.143 -0.5588)
			)
			(stroke
				(width 0)
				(type default)
			)
			(fill no)
			(layer "F.CrtYd")
		)
		(fp_line
			(start 0.508 0.3048)
			(end 0.508 -0.3048)
			(stroke
				(width 0.1)
				(type default)
			)
			(layer "F.Fab")
		)
		(fp_line
			(start 0.508 -0.3048)
			(end -0.508 -0.3048)
			(stroke
				(width 0.1)
				(type default)
			)
			(layer "F.Fab")
		)
		(fp_line
			(start -0.508 0.3048)
			(end 0.508 0.3048)
			(stroke
				(width 0.1)
				(type default)
			)
			(layer "F.Fab")
		)
		(fp_line
			(start -0.508 -0.3048)
			(end -0.508 0.3048)
			(stroke
				(width 0.1)
				(type default)
			)
			(layer "F.Fab")
		)
		(pad "1" smd rect
			(at -0.5334 0 180)
			(size 0.7112 0.6096)
			(layers "F.Cu" "F.Mask" "F.Paste")
			(net "FPGA_OUT_SMA4_LED_RED_N")
		)
		(pad "2" smd rect
			(at 0.5334 0 180)
			(size 0.7112 0.6096)
			(layers "F.Cu" "F.Mask" "F.Paste")
			(net "UNNAMED_14_LED4PV14_I268_3")
		)
		(zone
			(layer "F.Cu")
			(hatch none 0.5)
			(connect_pads
				(clearance 0)
			)
			(min_thickness 0.25)
			(keepout
				(tracks allowed)
				(vias not_allowed)
				(pads allowed)
				(copperpour not_allowed)
				(footprints allowed)
			)
			(placement
				(enabled no)
				(sheetname "")
			)
			(fill
				(thermal_gap 0.5)
				(thermal_bridge_width 0.5)
				(island_removal_mode 0)
			)
			(polygon
				(pts
					(xy 19.544538 -47.0408) (xy 19.392138 -47.0408) (xy 19.392138 -46.4312) (xy 19.544538 -46.4312)
				)
			)
		)
		(zone
			(layer "F.Cu")
			(hatch none 0.5)
			(connect_pads
				(clearance 0)
			)
			(min_thickness 0.25)
			(keepout
				(tracks not_allowed)
				(vias allowed)
				(pads allowed)
				(copperpour not_allowed)
				(footprints allowed)
			)
			(placement
				(enabled no)
				(sheetname "")
			)
			(fill
				(thermal_gap 0.5)
				(thermal_bridge_width 0.5)
				(island_removal_mode 0)
			)
			(polygon
				(pts
					(xy 19.544538 -47.0408) (xy 19.392138 -47.0408) (xy 19.392138 -46.4312) (xy 19.544538 -46.4312)
				)
			)
		)
	)
	(footprint ""
		(layer "F.Cu")
		(at 115.443 -74.803)
		(property "Reference" "C236"
			(at 3.302 0.42037 0)
			(unlocked yes)
			(layer "F.SilkS")
			(effects
				(font
					(size 0.7874 0.5842)
					(thickness 0.1524)
				)
			)
		)
		(property "Value" "VAL*"
			(at 0.0762 2.067306 0)
			(unlocked yes)
			(layer "F.Fab")
			(hide yes)
			(effects
				(font
					(size 0.7874 0.5842)
					(thickness 0.1524)
				)
			)
		)
		(property "Device Type" "CAPACITOR-G105-0B104-EK,0.1UF,A"
			(at 0.0508 1.127506 0)
			(unlocked yes)
			(layer "F.Fab")
			(hide yes)
			(effects
				(font
					(size 0.7874 0.5842)
					(thickness 0.1524)
				)
			)
		)
		(property "User Part Number" "PARTNUM*"
			(at 0.1016 4.023106 0)
			(unlocked yes)
			(layer "Cmts.User")
			(hide yes)
			(effects
				(font
					(size 0.7874 0.5842)
					(thickness 0.1524)
				)
			)
		)
		(property "Tolerance" "TOL*"
			(at 0.0762 3.032506 0)
			(unlocked yes)
			(layer "Cmts.User")
			(hide yes)
			(effects
				(font
					(size 0.7874 0.5842)
					(thickness 0.1524)
				)
			)
		)
		(duplicate_pad_numbers_are_jumpers no)
		(fp_line
			(start -1.143 -0.5588)
			(end -1.143 0.5588)
			(stroke
				(width 0.1)
				(type default)
			)
			(layer "F.SilkS")
		)
		(fp_line
			(start -1.143 0.5588)
			(end 1.143 0.5588)
			(stroke
				(width 0.1)
				(type default)
			)
			(layer "F.SilkS")
		)
		(fp_line
			(start 1.143 -0.5588)
			(end -1.143 -0.5588)
			(stroke
				(width 0.1)
				(type default)
			)
			(layer "F.SilkS")
		)
		(fp_line
			(start 1.143 0.5588)
			(end 1.143 -0.5588)
			(stroke
				(width 0.1)
				(type default)
			)
			(layer "F.SilkS")
		)
		(fp_rect
			(start -1.143 0.5588)
			(end 1.143 -0.5588)
			(stroke
				(width 0)
				(type default)
			)
			(fill no)
			(layer "F.CrtYd")
		)
		(fp_line
			(start -0.508 -0.3048)
			(end -0.508 0.3048)
			(stroke
				(width 0.1)
				(type default)
			)
			(layer "F.Fab")
		)
		(fp_line
			(start -0.508 0.3048)
			(end 0.508 0.3048)
			(stroke
				(width 0.1)
				(type default)
			)
			(layer "F.Fab")
		)
		(fp_line
			(start 0.508 -0.3048)
			(end -0.508 -0.3048)
			(stroke
				(width 0.1)
				(type default)
			)
			(layer "F.Fab")
		)
		(fp_line
			(start 0.508 0.3048)
			(end 0.508 -0.3048)
			(stroke
				(width 0.1)
				(type default)
			)
			(layer "F.Fab")
		)
		(pad "1" smd rect
			(at -0.5334 0)
			(size 0.7112 0.6096)
			(layers "F.Cu" "F.Mask" "F.Paste")
			(net "XP3R3V_FPGA_SR")
		)
		(pad "2" smd rect
			(at 0.5334 0)
			(size 0.7112 0.6096)
			(layers "F.Cu" "F.Mask" "F.Paste")
			(net "SG")
		)
		(zone
			(layer "F.Cu")
			(hatch none 0.5)
			(connect_pads
				(clearance 0)
			)
			(min_thickness 0.25)
			(keepout
				(tracks allowed)
				(vias not_allowed)
				(pads allowed)
				(copperpour not_allowed)
				(footprints allowed)
			)
			(placement
				(enabled no)
				(sheetname "")
			)
			(fill
				(thermal_gap 0.5)
				(thermal_bridge_width 0.5)
				(island_removal_mode 0)
			)
			(polygon
				(pts
					(xy 115.3668 -74.4982) (xy 115.5192 -74.4982) (xy 115.5192 -75.1078) (xy 115.3668 -75.1078)
				)
			)
		)
	)
)
